(kicad_pcb
	(version 20260206)
	(generator "pcbnew")
	(generator_version "10.0")
	(general
		(thickness 1.6)
		(legacy_teardrops no)
	)
	(paper "A4")
	(title_block
		(title "Wiwynn_Tioga_Pass_MB.brd")
		(comment 1 "Tioga Pass / footprint 2178 of 4770 (EU1G2), pads 1-41 of 41")
	)
	(layers
		(0 "F.Cu" signal "TOP")
		(4 "In1.Cu" signal "L2GND")
		(6 "In2.Cu" signal "L3")
		(8 "In3.Cu" signal "L4GND")
		(10 "In4.Cu" signal "L5")
		(12 "In5.Cu" signal "L6GND")
		(14 "In6.Cu" signal "L7VCC")
		(16 "In7.Cu" signal "L8VCC")
		(18 "In8.Cu" signal "L9GND")
		(20 "In9.Cu" signal "L10")
		(22 "In10.Cu" signal "L11GND")
		(24 "In11.Cu" signal "L12")
		(26 "In12.Cu" signal "L13GND")
		(2 "B.Cu" signal "BOTTOM")
		(9 "F.Adhes" user "F.Adhesive")
		(11 "B.Adhes" user "B.Adhesive")
		(13 "F.Paste" user "Package Geometry/Pastemask Top")
		(15 "B.Paste" user "Package Geometry/Pastemask Bottom")
		(5 "F.SilkS" user "Ref Des/Silkscreen Top")
		(7 "B.SilkS" user "Ref Des/Silkscreen Bottom")
		(1 "F.Mask" user "Board Geometry/Soldermask Top")
		(3 "B.Mask" user "Board Geometry/Soldermask Bottom")
		(17 "Dwgs.User" user "User.Drawings")
		(19 "Cmts.User" user "User.Comments")
		(21 "Eco1.User" user "User.Eco1")
		(23 "Eco2.User" user "User.Eco2")
		(25 "Edge.Cuts" user "Board Geometry/Outline")
		(27 "Margin" user)
		(31 "F.CrtYd" user "Package Geometry/Place Bound Top")
		(29 "B.CrtYd" user "Package Geometry/Place Bound Bottom")
		(35 "F.Fab" user "Ref Des/Assembly Top")
		(33 "B.Fab" user "Ref Des/Assembly Bottom")
	)
	(footprint ""
		(layer "F.Cu")
		(at 10.033 0.24765 180)
		(property "Reference" "EU1G2"
			(at 2.4638 -3.53187 0)
			(unlocked yes)
			(layer "F.SilkS")
			(effects
				(font
					(size 0.7874 0.5842)
					(thickness 0.1524)
				)
				(justify left)
			)
		)
		(property "Value" ""
			(at 0 0 180)
			(layer "F.Fab")
			(effects
				(font
					(size 1.27 1.27)
				)
			)
		)
		(duplicate_pad_numbers_are_jumpers no)
		(pad "1" smd custom
			(at -2.4511 -1.800098 180)
			(size 0.0508 0.0508)
			(layers "F.Cu" "F.Mask" "F.Paste")
			(net "Net_285")
			(options
				(clearance outline)
				(anchor circle)
			)
			(primitives
				(gr_poly
					(pts
						(arc
							(start 0.254 -0.1016)
							(mid 0.3556 0)
							(end 0.254 0.1016)
						)
						(xy -0.3556 0.1016) (xy -0.3556 -0.1016)
					)
					(width 0)
					(fill yes)
				)
			)
		)
		(pad "2" smd custom
			(at -2.4511 -1.400048 180)
			(size 0.0508 0.0508)
			(layers "F.Cu" "F.Mask" "F.Paste")
			(net "Net_349")
			(options
				(clearance outline)
				(anchor circle)
			)
			(primitives
				(gr_poly
					(pts
						(arc
							(start 0.254 -0.1016)
							(mid 0.3556 0)
							(end 0.254 0.1016)
						)
						(xy -0.3556 0.1016) (xy -0.3556 -0.1016)
					)
					(width 0)
					(fill yes)
				)
			)
		)
		(pad "3" smd custom
			(at -2.4511 -0.999998 180)
			(size 0.0508 0.0508)
			(layers "F.Cu" "F.Mask" "F.Paste")
			(net "Net_316")
			(options
				(clearance outline)
				(anchor circle)
			)
			(primitives
				(gr_poly
					(pts
						(arc
							(start 0.254 -0.1016)
							(mid 0.3556 0)
							(end 0.254 0.1016)
						)
						(xy -0.3556 0.1016) (xy -0.3556 -0.1016)
					)
					(width 0)
					(fill yes)
				)
			)
		)
		(pad "4" smd custom
			(at -2.4511 -0.599948 180)
			(size 0.0508 0.0508)
			(layers "F.Cu" "F.Mask" "F.Paste")
			(net "VR_PVDDQ_GHJ_PWM2")
			(options
				(clearance outline)
				(anchor circle)
			)
			(primitives
				(gr_poly
					(pts
						(arc
							(start 0.254 -0.1016)
							(mid 0.3556 0)
							(end 0.254 0.1016)
						)
						(xy -0.3556 0.1016) (xy -0.3556 -0.1016)
					)
					(width 0)
					(fill yes)
				)
			)
		)
		(pad "5" smd custom
			(at -2.4511 -0.199898 180)
			(size 0.0508 0.0508)
			(layers "F.Cu" "F.Mask" "F.Paste")
			(net "VR_PVDDQ_GHJ_PWM1")
			(options
				(clearance outline)
				(anchor circle)
			)
			(primitives
				(gr_poly
					(pts
						(arc
							(start 0.254 -0.1016)
							(mid 0.3556 0)
							(end 0.254 0.1016)
						)
						(xy -0.3556 0.1016) (xy -0.3556 -0.1016)
					)
					(width 0)
					(fill yes)
				)
			)
		)
		(pad "6" smd custom
			(at -2.4511 0.199898 180)
			(size 0.0508 0.0508)
			(layers "F.Cu" "F.Mask" "F.Paste")
			(net "SMB_VR_STBY_LVC3_SDA")
			(options
				(clearance outline)
				(anchor circle)
			)
			(primitives
				(gr_poly
					(pts
						(arc
							(start 0.254 -0.1016)
							(mid 0.3556 0)
							(end 0.254 0.1016)
						)
						(xy -0.3556 0.1016) (xy -0.3556 -0.1016)
					)
					(width 0)
					(fill yes)
				)
			)
		)
		(pad "7" smd custom
			(at -2.4511 0.599948 180)
			(size 0.0508 0.0508)
			(layers "F.Cu" "F.Mask" "F.Paste")
			(net "SMB_VR_STBY_LVC3_SCL")
			(options
				(clearance outline)
				(anchor circle)
			)
			(primitives
				(gr_poly
					(pts
						(arc
							(start 0.254 -0.1016)
							(mid 0.3556 0)
							(end 0.254 0.1016)
						)
						(xy -0.3556 0.1016) (xy -0.3556 -0.1016)
					)
					(width 0)
					(fill yes)
				)
			)
		)
		(pad "8" smd custom
			(at -2.4511 0.999998 180)
			(size 0.0508 0.0508)
			(layers "F.Cu" "F.Mask" "F.Paste")
			(net "Net_286")
			(options
				(clearance outline)
				(anchor circle)
			)
			(primitives
				(gr_poly
					(pts
						(arc
							(start 0.254 -0.1016)
							(mid 0.3556 0)
							(end 0.254 0.1016)
						)
						(xy -0.3556 0.1016) (xy -0.3556 -0.1016)
					)
					(width 0)
					(fill yes)
				)
			)
		)
		(pad "9" smd custom
			(at -2.4511 1.400048 180)
			(size 0.0508 0.0508)
			(layers "F.Cu" "F.Mask" "F.Paste")
			(net "PWRGD_PVDDQ_GHJ_R")
			(options
				(clearance outline)
				(anchor circle)
			)
			(primitives
				(gr_poly
					(pts
						(arc
							(start 0.254 -0.1016)
							(mid 0.3556 0)
							(end 0.254 0.1016)
						)
						(xy -0.3556 0.1016) (xy -0.3556 -0.1016)
					)
					(width 0)
					(fill yes)
				)
			)
		)
		(pad "10" smd custom
			(at -2.4511 1.800098 180)
			(size 0.0508 0.0508)
			(layers "F.Cu" "F.Mask" "F.Paste")
			(net "VR_PVDDQ_GHJ_VREN")
			(options
				(clearance outline)
				(anchor circle)
			)
			(primitives
				(gr_poly
					(pts
						(arc
							(start 0.254 -0.1016)
							(mid 0.3556 0)
							(end 0.254 0.1016)
						)
						(xy -0.3556 0.1016) (xy -0.3556 -0.1016)
					)
					(width 0)
					(fill yes)
				)
			)
		)
		(pad "11" smd custom
			(at -1.800098 2.4511 180)
			(size 0.0508 0.0508)
			(layers "F.Cu" "F.Mask" "F.Paste")
			(net "IRQ_PVDDQ_GHJ_VRHOT_LVT3_R_N")
			(options
				(clearance outline)
				(anchor circle)
			)
			(primitives
				(gr_poly
					(pts
						(arc
							(start -0.1016 -0.254)
							(mid 0 -0.3556)
							(end 0.1016 -0.254)
						)
						(xy 0.1016 0.3556) (xy -0.1016 0.3556)
					)
					(width 0)
					(fill yes)
				)
			)
		)
		(pad "12" smd custom
			(at -1.400048 2.4511 180)
			(size 0.0508 0.0508)
			(layers "F.Cu" "F.Mask" "F.Paste")
			(net "Net_315")
			(options
				(clearance outline)
				(anchor circle)
			)
			(primitives
				(gr_poly
					(pts
						(arc
							(start -0.1016 -0.254)
							(mid 0 -0.3556)
							(end 0.1016 -0.254)
						)
						(xy 0.1016 0.3556) (xy -0.1016 0.3556)
					)
					(width 0)
					(fill yes)
				)
			)
		)
		(pad "13" smd custom
			(at -0.999998 2.4511 180)
			(size 0.0508 0.0508)
			(layers "F.Cu" "F.Mask" "F.Paste")
			(net "PU_VR_PVDDQ_GHJ_FAULT1")
			(options
				(clearance outline)
				(anchor circle)
			)
			(primitives
				(gr_poly
					(pts
						(arc
							(start -0.1016 -0.254)
							(mid 0 -0.3556)
							(end 0.1016 -0.254)
						)
						(xy 0.1016 0.3556) (xy -0.1016 0.3556)
					)
					(width 0)
					(fill yes)
				)
			)
		)
		(pad "14" smd custom
			(at -0.599948 2.4511 180)
			(size 0.0508 0.0508)
			(layers "F.Cu" "F.Mask" "F.Paste")
			(net "TP_PVDDQ_GHJ_MP1")
			(options
				(clearance outline)
				(anchor circle)
			)
			(primitives
				(gr_poly
					(pts
						(arc
							(start -0.1016 -0.254)
							(mid 0 -0.3556)
							(end 0.1016 -0.254)
						)
						(xy 0.1016 0.3556) (xy -0.1016 0.3556)
					)
					(width 0)
					(fill yes)
				)
			)
		)
		(pad "15" smd custom
			(at -0.199898 2.4511 180)
			(size 0.0508 0.0508)
			(layers "F.Cu" "F.Mask" "F.Paste")
			(net "SVID_CLK_PVDDQ_GHJ")
			(options
				(clearance outline)
				(anchor circle)
			)
			(primitives
				(gr_poly
					(pts
						(arc
							(start -0.1016 -0.254)
							(mid 0 -0.3556)
							(end 0.1016 -0.254)
						)
						(xy 0.1016 0.3556) (xy -0.1016 0.3556)
					)
					(width 0)
					(fill yes)
				)
			)
		)
		(pad "16" smd custom
			(at 0.199898 2.4511 180)
			(size 0.0508 0.0508)
			(layers "F.Cu" "F.Mask" "F.Paste")
			(net "SVID_VDIO_PVDDQ_GHJ")
			(options
				(clearance outline)
				(anchor circle)
			)
			(primitives
				(gr_poly
					(pts
						(arc
							(start -0.1016 -0.254)
							(mid 0 -0.3556)
							(end 0.1016 -0.254)
						)
						(xy 0.1016 0.3556) (xy -0.1016 0.3556)
					)
					(width 0)
					(fill yes)
				)
			)
		)
		(pad "17" smd custom
			(at 0.599948 2.4511 180)
			(size 0.0508 0.0508)
			(layers "F.Cu" "F.Mask" "F.Paste")
			(net "SVID_ALERT_PVDDQ_GHJ")
			(options
				(clearance outline)
				(anchor circle)
			)
			(primitives
				(gr_poly
					(pts
						(arc
							(start -0.1016 -0.254)
							(mid 0 -0.3556)
							(end 0.1016 -0.254)
						)
						(xy 0.1016 0.3556) (xy -0.1016 0.3556)
					)
					(width 0)
					(fill yes)
				)
			)
		)
		(pad "18" smd custom
			(at 0.999998 2.4511 180)
			(size 0.0508 0.0508)
			(layers "F.Cu" "F.Mask" "F.Paste")
			(net "TP_PVDDQ_GHJ_MP2")
			(options
				(clearance outline)
				(anchor circle)
			)
			(primitives
				(gr_poly
					(pts
						(arc
							(start -0.1016 -0.254)
							(mid 0 -0.3556)
							(end 0.1016 -0.254)
						)
						(xy 0.1016 0.3556) (xy -0.1016 0.3556)
					)
					(width 0)
					(fill yes)
				)
			)
		)
		(pad "19" smd custom
			(at 1.400048 2.4511 180)
			(size 0.0508 0.0508)
			(layers "F.Cu" "F.Mask" "F.Paste")
			(net "VR_PVDDQ_GHJ_AVSP")
			(options
				(clearance outline)
				(anchor circle)
			)
			(primitives
				(gr_poly
					(pts
						(arc
							(start -0.1016 -0.254)
							(mid 0 -0.3556)
							(end 0.1016 -0.254)
						)
						(xy 0.1016 0.3556) (xy -0.1016 0.3556)
					)
					(width 0)
					(fill yes)
				)
			)
		)
		(pad "20" smd custom
			(at 1.800098 2.4511 180)
			(size 0.0508 0.0508)
			(layers "F.Cu" "F.Mask" "F.Paste")
			(net "VSENSE_PVDDQ_GHJ_N")
			(options
				(clearance outline)
				(anchor circle)
			)
			(primitives
				(gr_poly
					(pts
						(arc
							(start -0.1016 -0.254)
							(mid 0 -0.3556)
							(end 0.1016 -0.254)
						)
						(xy 0.1016 0.3556) (xy -0.1016 0.3556)
					)
					(width 0)
					(fill yes)
				)
			)
		)
		(pad "21" smd custom
			(at 2.4511 1.800098 180)
			(size 0.0508 0.0508)
			(layers "F.Cu" "F.Mask" "F.Paste")
			(net "VR_PVDDQ_GHJ_AIREF1")
			(options
				(clearance outline)
				(anchor circle)
			)
			(primitives
				(gr_poly
					(pts
						(arc
							(start -0.254 0.1016)
							(mid -0.3556 0)
							(end -0.254 -0.1016)
						)
						(xy 0.3556 -0.1016) (xy 0.3556 0.1016)
					)
					(width 0)
					(fill yes)
				)
			)
		)
		(pad "22" smd custom
			(at 2.4511 1.400048 180)
			(size 0.0508 0.0508)
			(layers "F.Cu" "F.Mask" "F.Paste")
			(net "ISENSE_PVDDQ_GHJ_PH1_IMON")
			(options
				(clearance outline)
				(anchor circle)
			)
			(primitives
				(gr_poly
					(pts
						(arc
							(start -0.254 0.1016)
							(mid -0.3556 0)
							(end -0.254 -0.1016)
						)
						(xy 0.3556 -0.1016) (xy 0.3556 0.1016)
					)
					(width 0)
					(fill yes)
				)
			)
		)
		(pad "23" smd custom
			(at 2.4511 0.999998 180)
			(size 0.0508 0.0508)
			(layers "F.Cu" "F.Mask" "F.Paste")
			(net "VR_PVDDQ_GHJ_AIREF2")
			(options
				(clearance outline)
				(anchor circle)
			)
			(primitives
				(gr_poly
					(pts
						(arc
							(start -0.254 0.1016)
							(mid -0.3556 0)
							(end -0.254 -0.1016)
						)
						(xy 0.3556 -0.1016) (xy 0.3556 0.1016)
					)
					(width 0)
					(fill yes)
				)
			)
		)
		(pad "24" smd custom
			(at 2.4511 0.599948 180)
			(size 0.0508 0.0508)
			(layers "F.Cu" "F.Mask" "F.Paste")
			(net "ISENSE_PVDDQ_GHJ_PH2_IMON")
			(options
				(clearance outline)
				(anchor circle)
			)
			(primitives
				(gr_poly
					(pts
						(arc
							(start -0.254 0.1016)
							(mid -0.3556 0)
							(end -0.254 -0.1016)
						)
						(xy 0.3556 -0.1016) (xy 0.3556 0.1016)
					)
					(width 0)
					(fill yes)
				)
			)
		)
		(pad "25" smd custom
			(at 2.4511 0.199898 180)
			(size 0.0508 0.0508)
			(layers "F.Cu" "F.Mask" "F.Paste")
			(net "Net_247")
			(options
				(clearance outline)
				(anchor circle)
			)
			(primitives
				(gr_poly
					(pts
						(arc
							(start -0.254 0.1016)
							(mid -0.3556 0)
							(end -0.254 -0.1016)
						)
						(xy 0.3556 -0.1016) (xy 0.3556 0.1016)
					)
					(width 0)
					(fill yes)
				)
			)
		)
		(pad "26" smd custom
			(at 2.4511 -0.199898 180)
			(size 0.0508 0.0508)
			(layers "F.Cu" "F.Mask" "F.Paste")
			(net "Net_246")
			(options
				(clearance outline)
				(anchor circle)
			)
			(primitives
				(gr_poly
					(pts
						(arc
							(start -0.254 0.1016)
							(mid -0.3556 0)
							(end -0.254 -0.1016)
						)
						(xy 0.3556 -0.1016) (xy 0.3556 0.1016)
					)
					(width 0)
					(fill yes)
				)
			)
		)
		(pad "27" smd custom
			(at 2.4511 -0.599948 180)
			(size 0.0508 0.0508)
			(layers "F.Cu" "F.Mask" "F.Paste")
			(net "GND")
			(options
				(clearance outline)
				(anchor circle)
			)
			(primitives
				(gr_poly
					(pts
						(arc
							(start -0.254 0.1016)
							(mid -0.3556 0)
							(end -0.254 -0.1016)
						)
						(xy 0.3556 -0.1016) (xy 0.3556 0.1016)
					)
					(width 0)
					(fill yes)
				)
			)
		)
		(pad "28" smd custom
			(at 2.4511 -0.999998 180)
			(size 0.0508 0.0508)
			(layers "F.Cu" "F.Mask" "F.Paste")
			(net "Net_350")
			(options
				(clearance outline)
				(anchor circle)
			)
			(primitives
				(gr_poly
					(pts
						(arc
							(start -0.254 0.1016)
							(mid -0.3556 0)
							(end -0.254 -0.1016)
						)
						(xy 0.3556 -0.1016) (xy 0.3556 0.1016)
					)
					(width 0)
					(fill yes)
				)
			)
		)
		(pad "29" smd custom
			(at 2.4511 -1.400048 180)
			(size 0.0508 0.0508)
			(layers "F.Cu" "F.Mask" "F.Paste")
			(net "Net_234")
			(options
				(clearance outline)
				(anchor circle)
			)
			(primitives
				(gr_poly
					(pts
						(arc
							(start -0.254 0.1016)
							(mid -0.3556 0)
							(end -0.254 -0.1016)
						)
						(xy 0.3556 -0.1016) (xy 0.3556 0.1016)
					)
					(width 0)
					(fill yes)
				)
			)
		)
		(pad "30" smd custom
			(at 2.4511 -1.800098 180)
			(size 0.0508 0.0508)
			(layers "F.Cu" "F.Mask" "F.Paste")
			(net "Net_233")
			(options
				(clearance outline)
				(anchor circle)
			)
			(primitives
				(gr_poly
					(pts
						(arc
							(start -0.254 0.1016)
							(mid -0.3556 0)
							(end -0.254 -0.1016)
						)
						(xy 0.3556 -0.1016) (xy 0.3556 0.1016)
					)
					(width 0)
					(fill yes)
				)
			)
		)
		(pad "31" smd custom
			(at 1.800098 -2.4511 180)
			(size 0.0508 0.0508)
			(layers "F.Cu" "F.Mask" "F.Paste")
			(net "Net_231")
			(options
				(clearance outline)
				(anchor circle)
			)
			(primitives
				(gr_poly
					(pts
						(arc
							(start 0.1016 0.254)
							(mid 0 0.3556)
							(end -0.1016 0.254)
						)
						(xy -0.1016 -0.3556) (xy 0.1016 -0.3556)
					)
					(width 0)
					(fill yes)
				)
			)
		)
		(pad "32" smd custom
			(at 1.400048 -2.4511 180)
			(size 0.0508 0.0508)
			(layers "F.Cu" "F.Mask" "F.Paste")
			(net "GND")
			(options
				(clearance outline)
				(anchor circle)
			)
			(primitives
				(gr_poly
					(pts
						(arc
							(start 0.1016 0.254)
							(mid 0 0.3556)
							(end -0.1016 0.254)
						)
						(xy -0.1016 -0.3556) (xy 0.1016 -0.3556)
					)
					(width 0)
					(fill yes)
				)
			)
		)
		(pad "33" smd custom
			(at 0.999998 -2.4511 180)
			(size 0.0508 0.0508)
			(layers "F.Cu" "F.Mask" "F.Paste")
			(net "VR_PVDDQ_GHJ_XADDR2")
			(options
				(clearance outline)
				(anchor circle)
			)
			(primitives
				(gr_poly
					(pts
						(arc
							(start 0.1016 0.254)
							(mid 0 0.3556)
							(end -0.1016 0.254)
						)
						(xy -0.1016 -0.3556) (xy 0.1016 -0.3556)
					)
					(width 0)
					(fill yes)
				)
			)
		)
		(pad "34" smd custom
			(at 0.599948 -2.4511 180)
			(size 0.0508 0.0508)
			(layers "F.Cu" "F.Mask" "F.Paste")
			(net "Net_232")
			(options
				(clearance outline)
				(anchor circle)
			)
			(primitives
				(gr_poly
					(pts
						(arc
							(start 0.1016 0.254)
							(mid 0 0.3556)
							(end -0.1016 0.254)
						)
						(xy -0.1016 -0.3556) (xy 0.1016 -0.3556)
					)
					(width 0)
					(fill yes)
				)
			)
		)
		(pad "35" smd custom
			(at 0.199898 -2.4511 180)
			(size 0.0508 0.0508)
			(layers "F.Cu" "F.Mask" "F.Paste")
			(net "A_TSENSE_PVDDQ_GHJ")
			(options
				(clearance outline)
				(anchor circle)
			)
			(primitives
				(gr_poly
					(pts
						(arc
							(start 0.1016 0.254)
							(mid 0 0.3556)
							(end -0.1016 0.254)
						)
						(xy -0.1016 -0.3556) (xy 0.1016 -0.3556)
					)
					(width 0)
					(fill yes)
				)
			)
		)
		(pad "36" smd custom
			(at -0.199898 -2.4511 180)
			(size 0.0508 0.0508)
			(layers "F.Cu" "F.Mask" "F.Paste")
			(net "VR_PVDDQ_GHJ_XADDR1")
			(options
				(clearance outline)
				(anchor circle)
			)
			(primitives
				(gr_poly
					(pts
						(arc
							(start 0.1016 0.254)
							(mid 0 0.3556)
							(end -0.1016 0.254)
						)
						(xy -0.1016 -0.3556) (xy 0.1016 -0.3556)
					)
					(width 0)
					(fill yes)
				)
			)
		)
		(pad "37" smd custom
			(at -0.599948 -2.4511 180)
			(size 0.0508 0.0508)
			(layers "F.Cu" "F.Mask" "F.Paste")
			(net "VR_PVDDQ_GHJ_VINSEN")
			(options
				(clearance outline)
				(anchor circle)
			)
			(primitives
				(gr_poly
					(pts
						(arc
							(start 0.1016 0.254)
							(mid 0 0.3556)
							(end -0.1016 0.254)
						)
						(xy -0.1016 -0.3556) (xy 0.1016 -0.3556)
					)
					(width 0)
					(fill yes)
				)
			)
		)
		(pad "38" smd custom
			(at -0.999998 -2.4511 180)
			(size 0.0508 0.0508)
			(layers "F.Cu" "F.Mask" "F.Paste")
			(net "VR_PVDDQ_GHJ_AIINSEN")
			(options
				(clearance outline)
				(anchor circle)
			)
			(primitives
				(gr_poly
					(pts
						(arc
							(start 0.1016 0.254)
							(mid 0 0.3556)
							(end -0.1016 0.254)
						)
						(xy -0.1016 -0.3556) (xy 0.1016 -0.3556)
					)
					(width 0)
					(fill yes)
				)
			)
		)
		(pad "39" smd custom
			(at -1.400048 -2.4511 180)
			(size 0.0508 0.0508)
			(layers "F.Cu" "F.Mask" "F.Paste")
			(net "VR_PVDDQ_GHJ_VDD")
			(options
				(clearance outline)
				(anchor circle)
			)
			(primitives
				(gr_poly
					(pts
						(arc
							(start 0.1016 0.254)
							(mid 0 0.3556)
							(end -0.1016 0.254)
						)
						(xy -0.1016 -0.3556) (xy 0.1016 -0.3556)
					)
					(width 0)
					(fill yes)
				)
			)
		)
		(pad "40" smd custom
			(at -1.800098 -2.4511 180)
			(size 0.0508 0.0508)
			(layers "F.Cu" "F.Mask" "F.Paste")
			(net "VR_PVDDQ_GHJ_VD12")
			(options
				(clearance outline)
				(anchor circle)
			)
			(primitives
				(gr_poly
					(pts
						(arc
							(start 0.1016 0.254)
							(mid 0 0.3556)
							(end -0.1016 0.254)
						)
						(xy -0.1016 -0.3556) (xy 0.1016 -0.3556)
					)
					(width 0)
					(fill yes)
				)
			)
		)
		(pad "41" smd rect
			(at 0 0 180)
			(size 3.683 3.683)
			(layers "F.Cu" "F.Mask" "F.Paste")
			(net "GND")
		)
	)
)
